# S9S_MB_2U (Grand Teton) — schematic netlist excerpt (pin names and nets, part order shuffled) for the footprints in the layout excerpt that follows; sources: Cadence DE-HDL packaged netlist, KiCad conversion of 03242023_DA0F0TMBIJ0_F0T_Motherboard_J_brd_V01_OCP.brd

R1235  Q_RES  240 1% EMPTY  pkg 0402LF  page 119 : A = GND ; B = PUD_XTAL_CPU1_MODE0
C1021  Q_CAP  22UF 4V 20% X6S  pkg C0402  page 74 : A = PVCCIN_CPU0 ; B = GND

(kicad_pcb
	(version 20260206)
	(generator "pcbnew")
	(generator_version "10.0")
	(general
		(thickness 1.6)
		(legacy_teardrops no)
	)
	(paper "A4")
	(title_block
		(title "03242023_DA0F0TMBIJ0_F0T_Motherboard_J_brd_V01_OCP.brd")
		(comment 1 "Grand Teton / footprints 2569-2570 of 6105")
	)
	(layers
		(0 "F.Cu" signal "TOP")
		(4 "In1.Cu" signal "GND")
		(6 "In2.Cu" signal "IN1")
		(8 "In3.Cu" signal "GND1")
		(10 "In4.Cu" signal "IN2")
		(12 "In5.Cu" signal "GND2")
		(14 "In6.Cu" signal "IN3")
		(16 "In7.Cu" signal "GND3")
		(18 "In8.Cu" signal "VCC")
		(20 "In9.Cu" signal "VCC1")
		(22 "In10.Cu" signal "GND4")
		(24 "In11.Cu" signal "IN4")
		(26 "In12.Cu" signal "GND5")
		(28 "In13.Cu" signal "IN5")
		(30 "In14.Cu" signal "GND6")
		(32 "In15.Cu" signal "IN6")
		(34 "In16.Cu" signal "GND7")
		(2 "B.Cu" signal "BOTTOM")
		(9 "F.Adhes" user "F.Adhesive")
		(11 "B.Adhes" user "B.Adhesive")
		(13 "F.Paste" user "Package Geometry/Pastemask Top")
		(15 "B.Paste" user "Package Geometry/Pastemask Bottom")
		(5 "F.SilkS" user "Ref Des/Silkscreen Top")
		(7 "B.SilkS" user "Ref Des/Silkscreen Bottom")
		(1 "F.Mask" user "Board Geometry/Soldermask Top")
		(3 "B.Mask" user "Board Geometry/Soldermask Bottom")
		(17 "Dwgs.User" user "User.Drawings")
		(19 "Cmts.User" user "User.Comments")
		(21 "Eco1.User" user "User.Eco1")
		(23 "Eco2.User" user "User.Eco2")
		(25 "Edge.Cuts" user "Board Geometry/Outline")
		(27 "Margin" user)
		(31 "F.CrtYd" user "Package Geometry/Place Bound Top")
		(29 "B.CrtYd" user "Package Geometry/Place Bound Bottom")
		(35 "F.Fab" user "Ref Des/Assembly Top")
		(33 "B.Fab" user "Ref Des/Assembly Bottom")
	)
	(footprint ""
		(layer "F.Cu")
		(at 367.44783 -244.03177 90)
		(property "Reference" "C1021"
			(at 0 0 90)
			(layer "F.SilkS")
			(hide yes)
			(effects
				(font
					(size 1.27 1.27)
				)
			)
		)
		(property "Value" ""
			(at 0 0 90)
			(layer "F.Fab")
			(effects
				(font
					(size 1.27 1.27)
				)
			)
		)
		(duplicate_pad_numbers_are_jumpers no)
		(fp_line
			(start 0.7874 -0.4064)
			(end 0.7874 0.4064)
			(stroke
				(width 0.1524)
				(type default)
			)
			(layer "F.SilkS")
		)
		(fp_line
			(start -0.7874 -0.4064)
			(end 0.7874 -0.4064)
			(stroke
				(width 0.1524)
				(type default)
			)
			(layer "F.SilkS")
		)
		(fp_line
			(start 0.7874 0.4064)
			(end -0.7874 0.4064)
			(stroke
				(width 0.1524)
				(type default)
			)
			(layer "F.SilkS")
		)
		(fp_line
			(start -0.7874 0.4064)
			(end -0.7874 -0.4064)
			(stroke
				(width 0.1524)
				(type default)
			)
			(layer "F.SilkS")
		)
		(fp_line
			(start -0.12065 -0.305054)
			(end -0.12065 -0.2794)
			(stroke
				(width 0.1)
				(type default)
			)
			(layer "F.Fab")
		)
		(fp_line
			(start -0.67945 -0.305054)
			(end -0.12065 -0.305054)
			(stroke
				(width 0.1)
				(type default)
			)
			(layer "F.Fab")
		)
		(fp_line
			(start 0.67945 -0.3048)
			(end 0.67945 0.3048)
			(stroke
				(width 0.1)
				(type default)
			)
			(layer "F.Fab")
		)
		(fp_line
			(start 0.12065 -0.3048)
			(end 0.67945 -0.3048)
			(stroke
				(width 0.1)
				(type default)
			)
			(layer "F.Fab")
		)
		(fp_line
			(start 0.12065 -0.2794)
			(end 0.12065 -0.3048)
			(stroke
				(width 0.1)
				(type default)
			)
			(layer "F.Fab")
		)
		(fp_line
			(start -0.12065 -0.2794)
			(end 0.12065 -0.2794)
			(stroke
				(width 0.1)
				(type default)
			)
			(layer "F.Fab")
		)
		(fp_line
			(start 0.120396 0.2794)
			(end -0.12065 0.2794)
			(stroke
				(width 0.1)
				(type default)
			)
			(layer "F.Fab")
		)
		(fp_line
			(start -0.12065 0.2794)
			(end -0.12065 0.3048)
			(stroke
				(width 0.1)
				(type default)
			)
			(layer "F.Fab")
		)
		(fp_line
			(start 0.67945 0.3048)
			(end 0.120396 0.3048)
			(stroke
				(width 0.1)
				(type default)
			)
			(layer "F.Fab")
		)
		(fp_line
			(start 0.120396 0.3048)
			(end 0.120396 0.2794)
			(stroke
				(width 0.1)
				(type default)
			)
			(layer "F.Fab")
		)
		(fp_line
			(start -0.12065 0.3048)
			(end -0.67945 0.3048)
			(stroke
				(width 0.1)
				(type default)
			)
			(layer "F.Fab")
		)
		(fp_line
			(start -0.67945 0.3048)
			(end -0.67945 -0.305054)
			(stroke
				(width 0.1)
				(type default)
			)
			(layer "F.Fab")
		)
		(pad "1" smd circle
			(at -0.40005 0 90)
			(size 0 0)
			(layers "F.Cu" "F.Mask" "F.Paste")
			(net "PVCCIN_CPU0")
		)
		(pad "2" smd circle
			(at 0.40005 0 90)
			(size 0 0)
			(layers "F.Cu" "F.Mask" "F.Paste")
			(net "GND")
		)
	)
	(footprint ""
		(layer "F.Cu")
		(at 193.95948 -350.510348 180)
		(property "Reference" "R1235"
			(at 0 0 180)
			(layer "F.SilkS")
			(hide yes)
			(effects
				(font
					(size 1.27 1.27)
				)
			)
		)
		(property "Value" ""
			(at 0 0 180)
			(layer "F.Fab")
			(effects
				(font
					(size 1.27 1.27)
				)
			)
		)
		(duplicate_pad_numbers_are_jumpers no)
		(fp_line
			(start 0.7874 0.4064)
			(end -0.7874 0.4064)
			(stroke
				(width 0.1524)
				(type default)
			)
			(layer "F.SilkS")
		)
		(fp_line
			(start 0.7874 -0.4064)
			(end 0.7874 0.4064)
			(stroke
				(width 0.1524)
				(type default)
			)
			(layer "F.SilkS")
		)
		(fp_line
			(start -0.7874 0.4064)
			(end -0.7874 -0.4064)
			(stroke
				(width 0.1524)
				(type default)
			)
			(layer "F.SilkS")
		)
		(fp_line
			(start -0.7874 -0.4064)
			(end 0.7874 -0.4064)
			(stroke
				(width 0.1524)
				(type default)
			)
			(layer "F.SilkS")
		)
		(fp_line
			(start 0.67945 0.3048)
			(end 0.120396 0.3048)
			(stroke
				(width 0.1)
				(type default)
			)
			(layer "F.Fab")
		)
		(fp_line
			(start 0.67945 -0.3048)
			(end 0.67945 0.3048)
			(stroke
				(width 0.1)
				(type default)
			)
			(layer "F.Fab")
		)
		(fp_line
			(start 0.12065 -0.2794)
			(end 0.12065 -0.3048)
			(stroke
				(width 0.1)
				(type default)
			)
			(layer "F.Fab")
		)
		(fp_line
			(start 0.12065 -0.3048)
			(end 0.67945 -0.3048)
			(stroke
				(width 0.1)
				(type default)
			)
			(layer "F.Fab")
		)
		(fp_line
			(start 0.120396 0.3048)
			(end 0.120396 0.2794)
			(stroke
				(width 0.1)
				(type default)
			)
			(layer "F.Fab")
		)
		(fp_line
			(start 0.120396 0.2794)
			(end -0.12065 0.2794)
			(stroke
				(width 0.1)
				(type default)
			)
			(layer "F.Fab")
		)
		(fp_line
			(start -0.12065 0.3048)
			(end -0.67945 0.3048)
			(stroke
				(width 0.1)
				(type default)
			)
			(layer "F.Fab")
		)
		(fp_line
			(start -0.12065 0.2794)
			(end -0.12065 0.3048)
			(stroke
				(width 0.1)
				(type default)
			)
			(layer "F.Fab")
		)
		(fp_line
			(start -0.12065 -0.2794)
			(end 0.12065 -0.2794)
			(stroke
				(width 0.1)
				(type default)
			)
			(layer "F.Fab")
		)
		(fp_line
			(start -0.12065 -0.305054)
			(end -0.12065 -0.2794)
			(stroke
				(width 0.1)
				(type default)
			)
			(layer "F.Fab")
		)
		(fp_line
			(start -0.67945 0.3048)
			(end -0.67945 -0.305054)
			(stroke
				(width 0.1)
				(type default)
			)
			(layer "F.Fab")
		)
		(fp_line
			(start -0.67945 -0.305054)
			(end -0.12065 -0.305054)
			(stroke
				(width 0.1)
				(type default)
			)
			(layer "F.Fab")
		)
		(pad "1" smd circle
			(at -0.40005 0 180)
			(size 0 0)
			(layers "F.Cu" "F.Mask" "F.Paste")
			(net "GND")
		)
		(pad "2" smd circle
			(at 0.40005 0 180)
			(size 0 0)
			(layers "F.Cu" "F.Mask" "F.Paste")
			(net "PUD_XTAL_CPU1_MODE0")
		)
	)
)
